(kicad_pcb
	(version 20260206)
	(generator "pcbnew")
	(generator_version "10.0")
	(general
		(thickness 1.6)
		(legacy_teardrops no)
	)
	(paper "A4")
	(title_block
		(title "04192023_DAF0TMB3IC0_F0TG_MB_C_brd_V02_OCP.brd")
		(comment 1 "Grand Teton / footprints 7488-7492 of 8354")
	)
	(layers
		(0 "F.Cu" signal "TOP")
		(4 "In1.Cu" signal "GND")
		(6 "In2.Cu" signal "IN1")
		(8 "In3.Cu" signal "GND1")
		(10 "In4.Cu" signal "IN2")
		(12 "In5.Cu" signal "GND2")
		(14 "In6.Cu" signal "IN3")
		(16 "In7.Cu" signal "GND3")
		(18 "In8.Cu" signal "VCC")
		(20 "In9.Cu" signal "VCC1")
		(22 "In10.Cu" signal "GND4")
		(24 "In11.Cu" signal "IN4")
		(26 "In12.Cu" signal "GND5")
		(28 "In13.Cu" signal "IN5")
		(30 "In14.Cu" signal "GND6")
		(32 "In15.Cu" signal "IN6")
		(34 "In16.Cu" signal "GND7")
		(2 "B.Cu" signal "BOTTOM")
		(9 "F.Adhes" user "F.Adhesive")
		(11 "B.Adhes" user "B.Adhesive")
		(13 "F.Paste" user "Package Geometry/Pastemask Top")
		(15 "B.Paste" user "Package Geometry/Pastemask Bottom")
		(5 "F.SilkS" user "Ref Des/Silkscreen Top")
		(7 "B.SilkS" user "Ref Des/Silkscreen Bottom")
		(1 "F.Mask" user "Board Geometry/Soldermask Top")
		(3 "B.Mask" user "Board Geometry/Soldermask Bottom")
		(17 "Dwgs.User" user "User.Drawings")
		(19 "Cmts.User" user "User.Comments")
		(21 "Eco1.User" user "User.Eco1")
		(23 "Eco2.User" user "User.Eco2")
		(25 "Edge.Cuts" user "Board Geometry/Outline")
		(27 "Margin" user)
		(31 "F.CrtYd" user "Package Geometry/Place Bound Top")
		(29 "B.CrtYd" user "Package Geometry/Place Bound Bottom")
		(35 "F.Fab" user "Ref Des/Assembly Top")
		(33 "B.Fab" user "Ref Des/Assembly Bottom")
	)
	(footprint ""
		(layer "B.Cu")
		(at 156.154374 -324.781672 180)
		(property "Reference" "R549"
			(at 0 0 0)
			(layer "B.SilkS")
			(hide yes)
			(effects
				(font
					(size 1.27 1.27)
				)
				(justify mirror)
			)
		)
		(property "Value" ""
			(at 0 0 0)
			(layer "B.Fab")
			(effects
				(font
					(size 1.27 1.27)
				)
				(justify mirror)
			)
		)
		(duplicate_pad_numbers_are_jumpers no)
		(fp_line
			(start 0.7874 0.4064)
			(end 0.7874 -0.4064)
			(stroke
				(width 0.1524)
				(type default)
			)
			(layer "B.SilkS")
		)
		(fp_line
			(start 0.7874 -0.4064)
			(end -0.7874 -0.4064)
			(stroke
				(width 0.1524)
				(type default)
			)
			(layer "B.SilkS")
		)
		(fp_line
			(start -0.7874 0.4064)
			(end 0.7874 0.4064)
			(stroke
				(width 0.1524)
				(type default)
			)
			(layer "B.SilkS")
		)
		(fp_line
			(start -0.7874 -0.4064)
			(end -0.7874 0.4064)
			(stroke
				(width 0.1524)
				(type default)
			)
			(layer "B.SilkS")
		)
		(fp_line
			(start 0.67945 0.3048)
			(end 0.67945 -0.305054)
			(stroke
				(width 0.1)
				(type default)
			)
			(layer "B.Fab")
		)
		(fp_line
			(start 0.67945 -0.305054)
			(end 0.12065 -0.305054)
			(stroke
				(width 0.1)
				(type default)
			)
			(layer "B.Fab")
		)
		(fp_line
			(start 0.12065 0.3048)
			(end 0.67945 0.3048)
			(stroke
				(width 0.1)
				(type default)
			)
			(layer "B.Fab")
		)
		(fp_line
			(start 0.12065 0.2794)
			(end 0.12065 0.3048)
			(stroke
				(width 0.1)
				(type default)
			)
			(layer "B.Fab")
		)
		(fp_line
			(start 0.12065 -0.2794)
			(end -0.12065 -0.2794)
			(stroke
				(width 0.1)
				(type default)
			)
			(layer "B.Fab")
		)
		(fp_line
			(start 0.12065 -0.305054)
			(end 0.12065 -0.2794)
			(stroke
				(width 0.1)
				(type default)
			)
			(layer "B.Fab")
		)
		(fp_line
			(start -0.120396 0.3048)
			(end -0.120396 0.2794)
			(stroke
				(width 0.1)
				(type default)
			)
			(layer "B.Fab")
		)
		(fp_line
			(start -0.120396 0.2794)
			(end 0.12065 0.2794)
			(stroke
				(width 0.1)
				(type default)
			)
			(layer "B.Fab")
		)
		(fp_line
			(start -0.12065 -0.2794)
			(end -0.12065 -0.3048)
			(stroke
				(width 0.1)
				(type default)
			)
			(layer "B.Fab")
		)
		(fp_line
			(start -0.12065 -0.3048)
			(end -0.67945 -0.3048)
			(stroke
				(width 0.1)
				(type default)
			)
			(layer "B.Fab")
		)
		(fp_line
			(start -0.67945 0.3048)
			(end -0.120396 0.3048)
			(stroke
				(width 0.1)
				(type default)
			)
			(layer "B.Fab")
		)
		(fp_line
			(start -0.67945 -0.3048)
			(end -0.67945 0.3048)
			(stroke
				(width 0.1)
				(type default)
			)
			(layer "B.Fab")
		)
		(pad "1" smd circle
			(at 0.40005 0)
			(size 0 0)
			(layers "B.Cu" "B.Mask" "B.Paste")
			(net "CPU1_SLP_S3_N")
		)
		(pad "2" smd circle
			(at -0.40005 0)
			(size 0 0)
			(layers "B.Cu" "B.Mask" "B.Paste")
			(net "PVDD18_S5_P1")
		)
	)
	(footprint ""
		(layer "B.Cu")
		(at 164.044376 -111.637572 180)
		(property "Reference" "R6140"
			(at 0 0 0)
			(layer "B.SilkS")
			(hide yes)
			(effects
				(font
					(size 1.27 1.27)
				)
				(justify mirror)
			)
		)
		(property "Value" ""
			(at 0 0 0)
			(layer "B.Fab")
			(effects
				(font
					(size 1.27 1.27)
				)
				(justify mirror)
			)
		)
		(duplicate_pad_numbers_are_jumpers no)
		(fp_line
			(start 0.7874 0.4064)
			(end 0.7874 -0.4064)
			(stroke
				(width 0.1524)
				(type default)
			)
			(layer "B.SilkS")
		)
		(fp_line
			(start 0.7874 -0.4064)
			(end -0.7874 -0.4064)
			(stroke
				(width 0.1524)
				(type default)
			)
			(layer "B.SilkS")
		)
		(fp_line
			(start -0.7874 0.4064)
			(end 0.7874 0.4064)
			(stroke
				(width 0.1524)
				(type default)
			)
			(layer "B.SilkS")
		)
		(fp_line
			(start -0.7874 -0.4064)
			(end -0.7874 0.4064)
			(stroke
				(width 0.1524)
				(type default)
			)
			(layer "B.SilkS")
		)
		(fp_line
			(start 0.67945 0.3048)
			(end 0.67945 -0.305054)
			(stroke
				(width 0.1)
				(type default)
			)
			(layer "B.Fab")
		)
		(fp_line
			(start 0.67945 -0.305054)
			(end 0.12065 -0.305054)
			(stroke
				(width 0.1)
				(type default)
			)
			(layer "B.Fab")
		)
		(fp_line
			(start 0.12065 0.3048)
			(end 0.67945 0.3048)
			(stroke
				(width 0.1)
				(type default)
			)
			(layer "B.Fab")
		)
		(fp_line
			(start 0.12065 0.2794)
			(end 0.12065 0.3048)
			(stroke
				(width 0.1)
				(type default)
			)
			(layer "B.Fab")
		)
		(fp_line
			(start 0.12065 -0.2794)
			(end -0.12065 -0.2794)
			(stroke
				(width 0.1)
				(type default)
			)
			(layer "B.Fab")
		)
		(fp_line
			(start 0.12065 -0.305054)
			(end 0.12065 -0.2794)
			(stroke
				(width 0.1)
				(type default)
			)
			(layer "B.Fab")
		)
		(fp_line
			(start -0.120396 0.3048)
			(end -0.120396 0.2794)
			(stroke
				(width 0.1)
				(type default)
			)
			(layer "B.Fab")
		)
		(fp_line
			(start -0.120396 0.2794)
			(end 0.12065 0.2794)
			(stroke
				(width 0.1)
				(type default)
			)
			(layer "B.Fab")
		)
		(fp_line
			(start -0.12065 -0.2794)
			(end -0.12065 -0.3048)
			(stroke
				(width 0.1)
				(type default)
			)
			(layer "B.Fab")
		)
		(fp_line
			(start -0.12065 -0.3048)
			(end -0.67945 -0.3048)
			(stroke
				(width 0.1)
				(type default)
			)
			(layer "B.Fab")
		)
		(fp_line
			(start -0.67945 0.3048)
			(end -0.120396 0.3048)
			(stroke
				(width 0.1)
				(type default)
			)
			(layer "B.Fab")
		)
		(fp_line
			(start -0.67945 -0.3048)
			(end -0.67945 0.3048)
			(stroke
				(width 0.1)
				(type default)
			)
			(layer "B.Fab")
		)
		(pad "1" smd circle
			(at 0.40005 0)
			(size 0 0)
			(layers "B.Cu" "B.Mask" "B.Paste")
			(net "P3V3_AUX")
		)
		(pad "2" smd circle
			(at -0.40005 0)
			(size 0 0)
			(layers "B.Cu" "B.Mask" "B.Paste")
			(net "FM_BOARD_BMC_SKU_ID0")
		)
	)
	(footprint ""
		(layer "B.Cu")
		(at 112.46866 -35.088068 90)
		(property "Reference" "C6110"
			(at 0 0 90)
			(layer "B.SilkS")
			(hide yes)
			(effects
				(font
					(size 1.27 1.27)
				)
				(justify mirror)
			)
		)
		(property "Value" ""
			(at 0 0 90)
			(layer "B.Fab")
			(effects
				(font
					(size 1.27 1.27)
				)
				(justify mirror)
			)
		)
		(duplicate_pad_numbers_are_jumpers no)
		(fp_line
			(start 0.7874 -0.4064)
			(end -0.7874 -0.4064)
			(stroke
				(width 0.1524)
				(type default)
			)
			(layer "B.SilkS")
		)
		(fp_line
			(start -0.7874 -0.4064)
			(end -0.7874 0.4064)
			(stroke
				(width 0.1524)
				(type default)
			)
			(layer "B.SilkS")
		)
		(fp_line
			(start 0.7874 0.4064)
			(end 0.7874 -0.4064)
			(stroke
				(width 0.1524)
				(type default)
			)
			(layer "B.SilkS")
		)
		(fp_line
			(start -0.7874 0.4064)
			(end 0.7874 0.4064)
			(stroke
				(width 0.1524)
				(type default)
			)
			(layer "B.SilkS")
		)
		(fp_line
			(start 0.67945 -0.305054)
			(end 0.12065 -0.305054)
			(stroke
				(width 0.1)
				(type default)
			)
			(layer "B.Fab")
		)
		(fp_line
			(start 0.12065 -0.305054)
			(end 0.12065 -0.2794)
			(stroke
				(width 0.1)
				(type default)
			)
			(layer "B.Fab")
		)
		(fp_line
			(start -0.12065 -0.3048)
			(end -0.67945 -0.3048)
			(stroke
				(width 0.1)
				(type default)
			)
			(layer "B.Fab")
		)
		(fp_line
			(start -0.67945 -0.3048)
			(end -0.67945 0.3048)
			(stroke
				(width 0.1)
				(type default)
			)
			(layer "B.Fab")
		)
		(fp_line
			(start 0.12065 -0.2794)
			(end -0.12065 -0.2794)
			(stroke
				(width 0.1)
				(type default)
			)
			(layer "B.Fab")
		)
		(fp_line
			(start -0.12065 -0.2794)
			(end -0.12065 -0.3048)
			(stroke
				(width 0.1)
				(type default)
			)
			(layer "B.Fab")
		)
		(fp_line
			(start 0.12065 0.2794)
			(end 0.12065 0.3048)
			(stroke
				(width 0.1)
				(type default)
			)
			(layer "B.Fab")
		)
		(fp_line
			(start -0.120396 0.2794)
			(end 0.12065 0.2794)
			(stroke
				(width 0.1)
				(type default)
			)
			(layer "B.Fab")
		)
		(fp_line
			(start 0.67945 0.3048)
			(end 0.67945 -0.305054)
			(stroke
				(width 0.1)
				(type default)
			)
			(layer "B.Fab")
		)
		(fp_line
			(start 0.12065 0.3048)
			(end 0.67945 0.3048)
			(stroke
				(width 0.1)
				(type default)
			)
			(layer "B.Fab")
		)
		(fp_line
			(start -0.120396 0.3048)
			(end -0.120396 0.2794)
			(stroke
				(width 0.1)
				(type default)
			)
			(layer "B.Fab")
		)
		(fp_line
			(start -0.67945 0.3048)
			(end -0.120396 0.3048)
			(stroke
				(width 0.1)
				(type default)
			)
			(layer "B.Fab")
		)
		(pad "1" smd circle
			(at 0.40005 0 270)
			(size 0 0)
			(layers "B.Cu" "B.Mask" "B.Paste")
			(net "P1V2_CPU0_USB2_DVDD12")
		)
		(pad "2" smd circle
			(at -0.40005 0 270)
			(size 0 0)
			(layers "B.Cu" "B.Mask" "B.Paste")
			(net "GND")
		)
	)
	(footprint ""
		(layer "B.Cu")
		(at 97.795842 3.523234 180)
		(property "Reference" "J118"
			(at 4.737608 -1.817624 270)
			(unlocked yes)
			(layer "B.SilkS")
			(effects
				(font
					(size 0.7874 0.5842)
					(thickness 0.1524)
				)
				(justify left mirror)
			)
		)
		(property "Value" ""
			(at 0 0 0)
			(layer "B.Fab")
			(effects
				(font
					(size 1.27 1.27)
				)
				(justify mirror)
			)
		)
		(duplicate_pad_numbers_are_jumpers no)
		(fp_line
			(start 1.2192 2.06756)
			(end 1.2192 -2.06756)
			(stroke
				(width 0.1524)
				(type default)
			)
			(layer "B.SilkS")
		)
		(fp_line
			(start 1.2192 -2.06756)
			(end -1.2192 -2.06756)
			(stroke
				(width 0.1524)
				(type default)
			)
			(layer "B.SilkS")
		)
		(fp_line
			(start -1.2192 2.06756)
			(end 1.2192 2.06756)
			(stroke
				(width 0.1524)
				(type default)
			)
			(layer "B.SilkS")
		)
		(fp_line
			(start -1.2192 -2.06756)
			(end -1.2192 2.06756)
			(stroke
				(width 0.1524)
				(type default)
			)
			(layer "B.SilkS")
		)
		(pad "" np_thru_hole circle
			(at -3.4671 -1.27 90)
			(size 1.0414 1.0414)
			(drill 1.0414)
			(layers "*.Cu" "*.Mask")
			(clearance 0.381)
			(thermal_gap 0.381)
		)
		(pad "" np_thru_hole circle
			(at -3.4671 1.27 90)
			(size 1.0414 1.0414)
			(drill 1.0414)
			(layers "*.Cu" "*.Mask")
			(clearance 0.381)
			(thermal_gap 0.381)
		)
		(pad "" np_thru_hole circle
			(at 2.8829 -1.27 90)
			(size 1.0414 1.0414)
			(drill 1.0414)
			(layers "*.Cu" "*.Mask")
			(clearance 0.381)
			(thermal_gap 0.381)
		)
		(pad "" np_thru_hole circle
			(at 2.8829 1.27 90)
			(size 1.0414 1.0414)
			(drill 1.0414)
			(layers "*.Cu" "*.Mask")
			(clearance 0.381)
			(thermal_gap 0.381)
		)
		(pad "1" smd rect
			(at -0.8255 -0.249936 90)
			(size 0.3048 0.508)
			(layers "B.Cu" "B.Mask" "B.Paste")
			(net "DELTA_L_85_10INCH_IN5_DP")
		)
		(pad "2" smd rect
			(at -0.8255 0.249936 90)
			(size 0.3048 0.508)
			(layers "B.Cu" "B.Mask" "B.Paste")
			(net "DELTA_L_85_10INCH_IN5_DN")
		)
		(pad "3" smd circle
			(at 0 0)
			(size 0 0)
			(layers "B.Cu" "B.Mask" "B.Paste")
			(net "DELTA_L_GND_1")
		)
		(zone
			(layers "F.Cu" "B.Cu" "In1.Cu" "In2.Cu" "In3.Cu" "In4.Cu" "In5.Cu" "In6.Cu"
				"In7.Cu" "In8.Cu" "In9.Cu" "In10.Cu" "In11.Cu" "In12.Cu" "In13.Cu" "In14.Cu"
				"In15.Cu" "In16.Cu"
			)
			(hatch none 0.5)
			(connect_pads
				(clearance 0)
			)
			(min_thickness 0.25)
			(keepout
				(tracks not_allowed)
				(vias allowed)
				(pads allowed)
				(copperpour not_allowed)
				(footprints allowed)
			)
			(placement
				(enabled no)
				(sheetname "")
			)
			(fill
				(thermal_gap 0.5)
				(thermal_bridge_width 0.5)
				(island_removal_mode 0)
			)
			(polygon
				(pts
					(arc
						(start 95.840042 2.253234)
						(mid 93.985842 2.253234)
						(end 95.840042 2.253234)
					)
				)
			)
		)
		(zone
			(layers "F.Cu" "B.Cu" "In1.Cu" "In2.Cu" "In3.Cu" "In4.Cu" "In5.Cu" "In6.Cu"
				"In7.Cu" "In8.Cu" "In9.Cu" "In10.Cu" "In11.Cu" "In12.Cu" "In13.Cu" "In14.Cu"
				"In15.Cu" "In16.Cu"
			)
			(hatch none 0.5)
			(connect_pads
				(clearance 0)
			)
			(min_thickness 0.25)
			(keepout
				(tracks not_allowed)
				(vias allowed)
				(pads allowed)
				(copperpour not_allowed)
				(footprints allowed)
			)
			(placement
				(enabled no)
				(sheetname "")
			)
			(fill
				(thermal_gap 0.5)
				(thermal_bridge_width 0.5)
				(island_removal_mode 0)
			)
			(polygon
				(pts
					(arc
						(start 95.840042 4.793234)
						(mid 93.985842 4.793234)
						(end 95.840042 4.793234)
					)
				)
			)
		)
		(zone
			(layers "F.Cu" "B.Cu" "In1.Cu" "In2.Cu" "In3.Cu" "In4.Cu" "In5.Cu" "In6.Cu"
				"In7.Cu" "In8.Cu" "In9.Cu" "In10.Cu" "In11.Cu" "In12.Cu" "In13.Cu" "In14.Cu"
				"In15.Cu" "In16.Cu"
			)
			(hatch none 0.5)
			(connect_pads
				(clearance 0)
			)
			(min_thickness 0.25)
			(keepout
				(tracks not_allowed)
				(vias allowed)
				(pads allowed)
				(copperpour not_allowed)
				(footprints allowed)
			)
			(placement
				(enabled no)
				(sheetname "")
			)
			(fill
				(thermal_gap 0.5)
				(thermal_bridge_width 0.5)
				(island_removal_mode 0)
			)
			(polygon
				(pts
					(arc
						(start 102.190042 2.253234)
						(mid 100.335842 2.253234)
						(end 102.190042 2.253234)
					)
				)
			)
		)
		(zone
			(layers "F.Cu" "B.Cu" "In1.Cu" "In2.Cu" "In3.Cu" "In4.Cu" "In5.Cu" "In6.Cu"
				"In7.Cu" "In8.Cu" "In9.Cu" "In10.Cu" "In11.Cu" "In12.Cu" "In13.Cu" "In14.Cu"
				"In15.Cu" "In16.Cu"
			)
			(hatch none 0.5)
			(connect_pads
				(clearance 0)
			)
			(min_thickness 0.25)
			(keepout
				(tracks not_allowed)
				(vias allowed)
				(pads allowed)
				(copperpour not_allowed)
				(footprints allowed)
			)
			(placement
				(enabled no)
				(sheetname "")
			)
			(fill
				(thermal_gap 0.5)
				(thermal_bridge_width 0.5)
				(island_removal_mode 0)
			)
			(polygon
				(pts
					(arc
						(start 102.190042 4.793234)
						(mid 100.335842 4.793234)
						(end 102.190042 4.793234)
					)
				)
			)
		)
		(zone
			(layer "B.Cu")
			(hatch none 0.5)
			(connect_pads
				(clearance 0)
			)
			(min_thickness 0.25)
			(keepout
				(tracks not_allowed)
				(vias allowed)
				(pads allowed)
				(copperpour not_allowed)
				(footprints allowed)
			)
			(placement
				(enabled no)
				(sheetname "")
			)
			(fill
				(thermal_gap 0.5)
				(thermal_bridge_width 0.5)
				(island_removal_mode 0)
			)
			(polygon
				(pts
					(xy 98.913442 4.071874) (xy 98.913442 3.97637) (xy 98.316542 3.97637) (xy 98.316542 3.56997) (xy 98.913442 3.56997)
					(xy 98.913442 3.476498) (xy 98.316542 3.476498) (xy 98.316542 3.070098) (xy 98.913442 3.070098)
					(xy 98.913442 2.974594) (xy 98.214942 2.974594) (xy 98.214942 4.071874)
				)
			)
		)
	)
	(footprint ""
		(layer "B.Cu")
		(at 124.078492 -386.766562 90)
		(property "Reference" "C445"
			(at 0 0 90)
			(layer "B.SilkS")
			(hide yes)
			(effects
				(font
					(size 1.27 1.27)
				)
				(justify mirror)
			)
		)
		(property "Value" ""
			(at 0 0 90)
			(layer "B.Fab")
			(effects
				(font
					(size 1.27 1.27)
				)
				(justify mirror)
			)
		)
		(duplicate_pad_numbers_are_jumpers no)
		(fp_line
			(start 0.299974 -0.150114)
			(end -0.299974 -0.150114)
			(stroke
				(width 0.1)
				(type default)
			)
			(layer "B.Fab")
		)
		(fp_line
			(start -0.299974 -0.150114)
			(end -0.299974 0.150114)
			(stroke
				(width 0.1)
				(type default)
			)
			(layer "B.Fab")
		)
		(fp_line
			(start 0.299974 0.150114)
			(end 0.299974 -0.150114)
			(stroke
				(width 0.1)
				(type default)
			)
			(layer "B.Fab")
		)
		(fp_line
			(start -0.299974 0.150114)
			(end 0.299974 0.150114)
			(stroke
				(width 0.1)
				(type default)
			)
			(layer "B.Fab")
		)
		(pad "1" smd rect
			(at 0.2667 0 270)
			(size 0.3048 0.381)
			(layers "B.Cu" "B.Mask" "B.Paste")
			(net "P1V8_CPU1_RT3_1A")
		)
		(pad "2" smd rect
			(at -0.2667 0 270)
			(size 0.3048 0.381)
			(layers "B.Cu" "B.Mask" "B.Paste")
			(net "GND")
		)
	)
)
